# S9S_MB_2U (Grand Teton) — schematic netlist excerpt (pin names and nets, part order shuffled) for the footprints in the layout excerpt that follows; sources: Cadence DE-HDL packaged netlist, KiCad conversion of 03242023_DA0F0TMBIJ0_F0T_Motherboard_J_brd_V01_OCP.brd

PC1194_P1_4  Q_CAP  3300PF 50V 10% X7R  pkg 0402  page 290 : A = SW_P12V_PVCCFA_EHV_FIVRA_CPU1_L ; B = GND
R4751  Q_RES  33.2 1% CHIP  pkg 0402LF  page 216 : A = HP_LVC3_OCP_V3_1_PWRGD_R ; B = HP_LVC3_OCP_V3_1_FUSE_PWRGD

(kicad_pcb
	(version 20260206)
	(generator "pcbnew")
	(generator_version "10.0")
	(general
		(thickness 1.6)
		(legacy_teardrops no)
	)
	(paper "A4")
	(title_block
		(title "03242023_DA0F0TMBIJ0_F0T_Motherboard_J_brd_V01_OCP.brd")
		(comment 1 "Grand Teton / footprints 465-466 of 6105")
	)
	(layers
		(0 "F.Cu" signal "TOP")
		(4 "In1.Cu" signal "GND")
		(6 "In2.Cu" signal "IN1")
		(8 "In3.Cu" signal "GND1")
		(10 "In4.Cu" signal "IN2")
		(12 "In5.Cu" signal "GND2")
		(14 "In6.Cu" signal "IN3")
		(16 "In7.Cu" signal "GND3")
		(18 "In8.Cu" signal "VCC")
		(20 "In9.Cu" signal "VCC1")
		(22 "In10.Cu" signal "GND4")
		(24 "In11.Cu" signal "IN4")
		(26 "In12.Cu" signal "GND5")
		(28 "In13.Cu" signal "IN5")
		(30 "In14.Cu" signal "GND6")
		(32 "In15.Cu" signal "IN6")
		(34 "In16.Cu" signal "GND7")
		(2 "B.Cu" signal "BOTTOM")
		(9 "F.Adhes" user "F.Adhesive")
		(11 "B.Adhes" user "B.Adhesive")
		(13 "F.Paste" user "Package Geometry/Pastemask Top")
		(15 "B.Paste" user "Package Geometry/Pastemask Bottom")
		(5 "F.SilkS" user "Ref Des/Silkscreen Top")
		(7 "B.SilkS" user "Ref Des/Silkscreen Bottom")
		(1 "F.Mask" user "Board Geometry/Soldermask Top")
		(3 "B.Mask" user "Board Geometry/Soldermask Bottom")
		(17 "Dwgs.User" user "User.Drawings")
		(19 "Cmts.User" user "User.Comments")
		(21 "Eco1.User" user "User.Eco1")
		(23 "Eco2.User" user "User.Eco2")
		(25 "Edge.Cuts" user "Board Geometry/Outline")
		(27 "Margin" user)
		(31 "F.CrtYd" user "Package Geometry/Place Bound Top")
		(29 "B.CrtYd" user "Package Geometry/Place Bound Bottom")
		(35 "F.Fab" user "Ref Des/Assembly Top")
		(33 "B.Fab" user "Ref Des/Assembly Bottom")
	)
	(footprint ""
		(layer "F.Cu")
		(at 46.178724 -353.61626 -90)
		(property "Reference" "PC1194_P1_4"
			(at 0 0 270)
			(layer "F.SilkS")
			(hide yes)
			(effects
				(font
					(size 1.27 1.27)
				)
			)
		)
		(property "Value" ""
			(at 0 0 270)
			(layer "F.Fab")
			(effects
				(font
					(size 1.27 1.27)
				)
			)
		)
		(duplicate_pad_numbers_are_jumpers no)
		(fp_line
			(start -0.7874 0.4064)
			(end -0.7874 -0.4064)
			(stroke
				(width 0.1524)
				(type default)
			)
			(layer "F.SilkS")
		)
		(fp_line
			(start 0.7874 0.4064)
			(end -0.7874 0.4064)
			(stroke
				(width 0.1524)
				(type default)
			)
			(layer "F.SilkS")
		)
		(fp_line
			(start -0.7874 -0.4064)
			(end 0.7874 -0.4064)
			(stroke
				(width 0.1524)
				(type default)
			)
			(layer "F.SilkS")
		)
		(fp_line
			(start 0.7874 -0.4064)
			(end 0.7874 0.4064)
			(stroke
				(width 0.1524)
				(type default)
			)
			(layer "F.SilkS")
		)
		(fp_line
			(start -0.67945 0.3048)
			(end -0.67945 -0.305054)
			(stroke
				(width 0.1)
				(type default)
			)
			(layer "F.Fab")
		)
		(fp_line
			(start -0.12065 0.3048)
			(end -0.67945 0.3048)
			(stroke
				(width 0.1)
				(type default)
			)
			(layer "F.Fab")
		)
		(fp_line
			(start 0.120396 0.3048)
			(end 0.120396 0.2794)
			(stroke
				(width 0.1)
				(type default)
			)
			(layer "F.Fab")
		)
		(fp_line
			(start 0.67945 0.3048)
			(end 0.120396 0.3048)
			(stroke
				(width 0.1)
				(type default)
			)
			(layer "F.Fab")
		)
		(fp_line
			(start -0.12065 0.2794)
			(end -0.12065 0.3048)
			(stroke
				(width 0.1)
				(type default)
			)
			(layer "F.Fab")
		)
		(fp_line
			(start 0.120396 0.2794)
			(end -0.12065 0.2794)
			(stroke
				(width 0.1)
				(type default)
			)
			(layer "F.Fab")
		)
		(fp_line
			(start -0.12065 -0.2794)
			(end 0.12065 -0.2794)
			(stroke
				(width 0.1)
				(type default)
			)
			(layer "F.Fab")
		)
		(fp_line
			(start 0.12065 -0.2794)
			(end 0.12065 -0.3048)
			(stroke
				(width 0.1)
				(type default)
			)
			(layer "F.Fab")
		)
		(fp_line
			(start 0.12065 -0.3048)
			(end 0.67945 -0.3048)
			(stroke
				(width 0.1)
				(type default)
			)
			(layer "F.Fab")
		)
		(fp_line
			(start 0.67945 -0.3048)
			(end 0.67945 0.3048)
			(stroke
				(width 0.1)
				(type default)
			)
			(layer "F.Fab")
		)
		(fp_line
			(start -0.67945 -0.305054)
			(end -0.12065 -0.305054)
			(stroke
				(width 0.1)
				(type default)
			)
			(layer "F.Fab")
		)
		(fp_line
			(start -0.12065 -0.305054)
			(end -0.12065 -0.2794)
			(stroke
				(width 0.1)
				(type default)
			)
			(layer "F.Fab")
		)
		(pad "1" smd circle
			(at -0.40005 0 270)
			(size 0 0)
			(layers "F.Cu" "F.Mask" "F.Paste")
			(net "SW_P12V_PVCCFA_EHV_FIVRA_CPU1_L")
		)
		(pad "2" smd circle
			(at 0.40005 0 270)
			(size 0 0)
			(layers "F.Cu" "F.Mask" "F.Paste")
			(net "GND")
		)
	)
	(footprint ""
		(layer "F.Cu")
		(at 186.8932 -93.91015 90)
		(property "Reference" "R4751"
			(at 0 0 90)
			(layer "F.SilkS")
			(hide yes)
			(effects
				(font
					(size 1.27 1.27)
				)
			)
		)
		(property "Value" ""
			(at 0 0 90)
			(layer "F.Fab")
			(effects
				(font
					(size 1.27 1.27)
				)
			)
		)
		(duplicate_pad_numbers_are_jumpers no)
		(fp_line
			(start 0.7874 -0.4064)
			(end 0.7874 0.4064)
			(stroke
				(width 0.1524)
				(type default)
			)
			(layer "F.SilkS")
		)
		(fp_line
			(start -0.7874 -0.4064)
			(end 0.7874 -0.4064)
			(stroke
				(width 0.1524)
				(type default)
			)
			(layer "F.SilkS")
		)
		(fp_line
			(start 0.7874 0.4064)
			(end -0.7874 0.4064)
			(stroke
				(width 0.1524)
				(type default)
			)
			(layer "F.SilkS")
		)
		(fp_line
			(start -0.7874 0.4064)
			(end -0.7874 -0.4064)
			(stroke
				(width 0.1524)
				(type default)
			)
			(layer "F.SilkS")
		)
		(fp_line
			(start -0.12065 -0.305054)
			(end -0.12065 -0.2794)
			(stroke
				(width 0.1)
				(type default)
			)
			(layer "F.Fab")
		)
		(fp_line
			(start -0.67945 -0.305054)
			(end -0.12065 -0.305054)
			(stroke
				(width 0.1)
				(type default)
			)
			(layer "F.Fab")
		)
		(fp_line
			(start 0.67945 -0.3048)
			(end 0.67945 0.3048)
			(stroke
				(width 0.1)
				(type default)
			)
			(layer "F.Fab")
		)
		(fp_line
			(start 0.12065 -0.3048)
			(end 0.67945 -0.3048)
			(stroke
				(width 0.1)
				(type default)
			)
			(layer "F.Fab")
		)
		(fp_line
			(start 0.12065 -0.2794)
			(end 0.12065 -0.3048)
			(stroke
				(width 0.1)
				(type default)
			)
			(layer "F.Fab")
		)
		(fp_line
			(start -0.12065 -0.2794)
			(end 0.12065 -0.2794)
			(stroke
				(width 0.1)
				(type default)
			)
			(layer "F.Fab")
		)
		(fp_line
			(start 0.120396 0.2794)
			(end -0.12065 0.2794)
			(stroke
				(width 0.1)
				(type default)
			)
			(layer "F.Fab")
		)
		(fp_line
			(start -0.12065 0.2794)
			(end -0.12065 0.3048)
			(stroke
				(width 0.1)
				(type default)
			)
			(layer "F.Fab")
		)
		(fp_line
			(start 0.67945 0.3048)
			(end 0.120396 0.3048)
			(stroke
				(width 0.1)
				(type default)
			)
			(layer "F.Fab")
		)
		(fp_line
			(start 0.120396 0.3048)
			(end 0.120396 0.2794)
			(stroke
				(width 0.1)
				(type default)
			)
			(layer "F.Fab")
		)
		(fp_line
			(start -0.12065 0.3048)
			(end -0.67945 0.3048)
			(stroke
				(width 0.1)
				(type default)
			)
			(layer "F.Fab")
		)
		(fp_line
			(start -0.67945 0.3048)
			(end -0.67945 -0.305054)
			(stroke
				(width 0.1)
				(type default)
			)
			(layer "F.Fab")
		)
		(pad "1" smd circle
			(at -0.40005 0 90)
			(size 0 0)
			(layers "F.Cu" "F.Mask" "F.Paste")
			(net "HP_LVC3_OCP_V3_1_PWRGD_R")
		)
		(pad "2" smd circle
			(at 0.40005 0 90)
			(size 0 0)
			(layers "F.Cu" "F.Mask" "F.Paste")
			(net "HP_LVC3_OCP_V3_1_FUSE_PWRGD")
		)
	)
)
